# T6G (Grand Teton) — schematic netlist excerpt (pin names and nets, part order shuffled) for the footprints in the layout excerpt that follows; sources: Cadence DE-HDL packaged netlist, KiCad conversion of 04192023_DAF0TMB3IC0_F0TG_MB_C_brd_V02_OCP.brd

Q12  MOSFET_N_GSD  NX138BK IC  pkg SOT23_GDSXE  page 166
  DRAIN  = P12V_ALL_PWROK_N
  GATE  = P12V_ALL_PWROK
  SOURCE  = GND

R4305  Q_RES  0 5% CHIP  pkg 0402LF  page 55 : A = CLK_100M_CPU1_CLK12_R_DP ; B = CLK_100M_CPU1_CLK12_DP
C2015  Q_CAP  0.1UF 25V 10% X7R  pkg 0402  page 236 : A = P3V3_AUX ; B = GND

(kicad_pcb
	(version 20260206)
	(generator "pcbnew")
	(generator_version "10.0")
	(general
		(thickness 1.6)
		(legacy_teardrops no)
	)
	(paper "A4")
	(title_block
		(title "04192023_DAF0TMB3IC0_F0TG_MB_C_brd_V02_OCP.brd")
		(comment 1 "Grand Teton / footprints 3219-3221 of 8354")
	)
	(layers
		(0 "F.Cu" signal "TOP")
		(4 "In1.Cu" signal "GND")
		(6 "In2.Cu" signal "IN1")
		(8 "In3.Cu" signal "GND1")
		(10 "In4.Cu" signal "IN2")
		(12 "In5.Cu" signal "GND2")
		(14 "In6.Cu" signal "IN3")
		(16 "In7.Cu" signal "GND3")
		(18 "In8.Cu" signal "VCC")
		(20 "In9.Cu" signal "VCC1")
		(22 "In10.Cu" signal "GND4")
		(24 "In11.Cu" signal "IN4")
		(26 "In12.Cu" signal "GND5")
		(28 "In13.Cu" signal "IN5")
		(30 "In14.Cu" signal "GND6")
		(32 "In15.Cu" signal "IN6")
		(34 "In16.Cu" signal "GND7")
		(2 "B.Cu" signal "BOTTOM")
		(9 "F.Adhes" user "F.Adhesive")
		(11 "B.Adhes" user "B.Adhesive")
		(13 "F.Paste" user "Package Geometry/Pastemask Top")
		(15 "B.Paste" user "Package Geometry/Pastemask Bottom")
		(5 "F.SilkS" user "Ref Des/Silkscreen Top")
		(7 "B.SilkS" user "Ref Des/Silkscreen Bottom")
		(1 "F.Mask" user "Board Geometry/Soldermask Top")
		(3 "B.Mask" user "Board Geometry/Soldermask Bottom")
		(17 "Dwgs.User" user "User.Drawings")
		(19 "Cmts.User" user "User.Comments")
		(21 "Eco1.User" user "User.Eco1")
		(23 "Eco2.User" user "User.Eco2")
		(25 "Edge.Cuts" user "Board Geometry/Outline")
		(27 "Margin" user)
		(31 "F.CrtYd" user "Package Geometry/Place Bound Top")
		(29 "B.CrtYd" user "Package Geometry/Place Bound Bottom")
		(35 "F.Fab" user "Ref Des/Assembly Top")
		(33 "B.Fab" user "Ref Des/Assembly Bottom")
	)
	(footprint ""
		(layer "F.Cu")
		(at 348.93123 -20.136612 -90)
		(property "Reference" "Q12"
			(at -3.219196 -2.33553 90)
			(unlocked yes)
			(layer "F.SilkS")
			(effects
				(font
					(size 0.7874 0.5842)
					(thickness 0.1524)
				)
			)
		)
		(property "Value" ""
			(at 0 0 270)
			(layer "F.Fab")
			(effects
				(font
					(size 1.27 1.27)
				)
			)
		)
		(duplicate_pad_numbers_are_jumpers no)
		(fp_line
			(start -1.8796 1.651)
			(end -1.8796 -1.651)
			(stroke
				(width 0.1524)
				(type default)
			)
			(layer "F.SilkS")
		)
		(fp_line
			(start 1.8796 1.651)
			(end -1.8796 1.651)
			(stroke
				(width 0.1524)
				(type default)
			)
			(layer "F.SilkS")
		)
		(fp_line
			(start -1.8796 -1.651)
			(end 1.8796 -1.651)
			(stroke
				(width 0.1524)
				(type default)
			)
			(layer "F.SilkS")
		)
		(fp_line
			(start 1.8796 -1.651)
			(end 1.8796 1.651)
			(stroke
				(width 0.1524)
				(type default)
			)
			(layer "F.SilkS")
		)
		(fp_line
			(start -0.700024 1.500124)
			(end -0.700024 -1.500124)
			(stroke
				(width 0.1)
				(type default)
			)
			(layer "F.Fab")
		)
		(fp_line
			(start 0.700024 1.500124)
			(end -0.700024 1.500124)
			(stroke
				(width 0.1)
				(type default)
			)
			(layer "F.Fab")
		)
		(fp_line
			(start -0.700024 -1.500124)
			(end 0.700024 -1.500124)
			(stroke
				(width 0.1)
				(type default)
			)
			(layer "F.Fab")
		)
		(fp_line
			(start 0.700024 -1.500124)
			(end 0.700024 1.500124)
			(stroke
				(width 0.1)
				(type default)
			)
			(layer "F.Fab")
		)
		(pad "D" smd rect
			(at 1.119886 0 180)
			(size 1.016 1.2192)
			(layers "F.Cu" "F.Mask" "F.Paste")
			(net "P12V_ALL_PWROK_N")
		)
		(pad "G" smd rect
			(at -1.119886 -0.999998 180)
			(size 1.016 1.2192)
			(layers "F.Cu" "F.Mask" "F.Paste")
			(net "P12V_ALL_PWROK")
		)
		(pad "S" smd rect
			(at -1.119886 0.999998 180)
			(size 1.016 1.2192)
			(layers "F.Cu" "F.Mask" "F.Paste")
			(net "GND")
		)
	)
	(footprint ""
		(layer "F.Cu")
		(at 438.277 -96.357948 90)
		(property "Reference" "C2015"
			(at 0 0 90)
			(layer "F.SilkS")
			(hide yes)
			(effects
				(font
					(size 1.27 1.27)
				)
			)
		)
		(property "Value" ""
			(at 0 0 90)
			(layer "F.Fab")
			(effects
				(font
					(size 1.27 1.27)
				)
			)
		)
		(duplicate_pad_numbers_are_jumpers no)
		(fp_line
			(start 0.7874 -0.4064)
			(end 0.7874 0.4064)
			(stroke
				(width 0.1524)
				(type default)
			)
			(layer "F.SilkS")
		)
		(fp_line
			(start -0.7874 -0.4064)
			(end 0.7874 -0.4064)
			(stroke
				(width 0.1524)
				(type default)
			)
			(layer "F.SilkS")
		)
		(fp_line
			(start 0.7874 0.4064)
			(end -0.7874 0.4064)
			(stroke
				(width 0.1524)
				(type default)
			)
			(layer "F.SilkS")
		)
		(fp_line
			(start -0.7874 0.4064)
			(end -0.7874 -0.4064)
			(stroke
				(width 0.1524)
				(type default)
			)
			(layer "F.SilkS")
		)
		(fp_line
			(start -0.12065 -0.305054)
			(end -0.12065 -0.2794)
			(stroke
				(width 0.1)
				(type default)
			)
			(layer "F.Fab")
		)
		(fp_line
			(start -0.67945 -0.305054)
			(end -0.12065 -0.305054)
			(stroke
				(width 0.1)
				(type default)
			)
			(layer "F.Fab")
		)
		(fp_line
			(start 0.67945 -0.3048)
			(end 0.67945 0.3048)
			(stroke
				(width 0.1)
				(type default)
			)
			(layer "F.Fab")
		)
		(fp_line
			(start 0.12065 -0.3048)
			(end 0.67945 -0.3048)
			(stroke
				(width 0.1)
				(type default)
			)
			(layer "F.Fab")
		)
		(fp_line
			(start 0.12065 -0.2794)
			(end 0.12065 -0.3048)
			(stroke
				(width 0.1)
				(type default)
			)
			(layer "F.Fab")
		)
		(fp_line
			(start -0.12065 -0.2794)
			(end 0.12065 -0.2794)
			(stroke
				(width 0.1)
				(type default)
			)
			(layer "F.Fab")
		)
		(fp_line
			(start 0.120396 0.2794)
			(end -0.12065 0.2794)
			(stroke
				(width 0.1)
				(type default)
			)
			(layer "F.Fab")
		)
		(fp_line
			(start -0.12065 0.2794)
			(end -0.12065 0.3048)
			(stroke
				(width 0.1)
				(type default)
			)
			(layer "F.Fab")
		)
		(fp_line
			(start 0.67945 0.3048)
			(end 0.120396 0.3048)
			(stroke
				(width 0.1)
				(type default)
			)
			(layer "F.Fab")
		)
		(fp_line
			(start 0.120396 0.3048)
			(end 0.120396 0.2794)
			(stroke
				(width 0.1)
				(type default)
			)
			(layer "F.Fab")
		)
		(fp_line
			(start -0.12065 0.3048)
			(end -0.67945 0.3048)
			(stroke
				(width 0.1)
				(type default)
			)
			(layer "F.Fab")
		)
		(fp_line
			(start -0.67945 0.3048)
			(end -0.67945 -0.305054)
			(stroke
				(width 0.1)
				(type default)
			)
			(layer "F.Fab")
		)
		(pad "1" smd circle
			(at -0.40005 0 90)
			(size 0 0)
			(layers "F.Cu" "F.Mask" "F.Paste")
			(net "P3V3_AUX")
		)
		(pad "2" smd circle
			(at 0.40005 0 90)
			(size 0 0)
			(layers "F.Cu" "F.Mask" "F.Paste")
			(net "GND")
		)
	)
	(footprint ""
		(layer "F.Cu")
		(at 122.809 -321.655948 90)
		(property "Reference" "R4305"
			(at 0 0 90)
			(layer "F.SilkS")
			(hide yes)
			(effects
				(font
					(size 1.27 1.27)
				)
			)
		)
		(property "Value" ""
			(at 0 0 90)
			(layer "F.Fab")
			(effects
				(font
					(size 1.27 1.27)
				)
			)
		)
		(duplicate_pad_numbers_are_jumpers no)
		(fp_line
			(start 0.7874 -0.4064)
			(end 0.7874 -0.0508)
			(stroke
				(width 0.1524)
				(type default)
			)
			(layer "F.SilkS")
		)
		(fp_line
			(start -0.7874 -0.4064)
			(end 0.7874 -0.4064)
			(stroke
				(width 0.1524)
				(type default)
			)
			(layer "F.SilkS")
		)
		(fp_line
			(start -0.7874 -0.0508)
			(end -0.7874 -0.4064)
			(stroke
				(width 0.1524)
				(type default)
			)
			(layer "F.SilkS")
		)
		(fp_line
			(start 0.416052 0.4064)
			(end -0.422148 0.4064)
			(stroke
				(width 0.1524)
				(type default)
			)
			(layer "F.SilkS")
		)
		(fp_line
			(start -0.12065 -0.305054)
			(end -0.12065 -0.2794)
			(stroke
				(width 0.1)
				(type default)
			)
			(layer "F.Fab")
		)
		(fp_line
			(start -0.67945 -0.305054)
			(end -0.12065 -0.305054)
			(stroke
				(width 0.1)
				(type default)
			)
			(layer "F.Fab")
		)
		(fp_line
			(start 0.67945 -0.3048)
			(end 0.67945 0.3048)
			(stroke
				(width 0.1)
				(type default)
			)
			(layer "F.Fab")
		)
		(fp_line
			(start 0.12065 -0.3048)
			(end 0.67945 -0.3048)
			(stroke
				(width 0.1)
				(type default)
			)
			(layer "F.Fab")
		)
		(fp_line
			(start 0.12065 -0.2794)
			(end 0.12065 -0.3048)
			(stroke
				(width 0.1)
				(type default)
			)
			(layer "F.Fab")
		)
		(fp_line
			(start -0.12065 -0.2794)
			(end 0.12065 -0.2794)
			(stroke
				(width 0.1)
				(type default)
			)
			(layer "F.Fab")
		)
		(fp_line
			(start 0.120396 0.2794)
			(end -0.12065 0.2794)
			(stroke
				(width 0.1)
				(type default)
			)
			(layer "F.Fab")
		)
		(fp_line
			(start -0.12065 0.2794)
			(end -0.12065 0.3048)
			(stroke
				(width 0.1)
				(type default)
			)
			(layer "F.Fab")
		)
		(fp_line
			(start 0.67945 0.3048)
			(end 0.120396 0.3048)
			(stroke
				(width 0.1)
				(type default)
			)
			(layer "F.Fab")
		)
		(fp_line
			(start 0.120396 0.3048)
			(end 0.120396 0.2794)
			(stroke
				(width 0.1)
				(type default)
			)
			(layer "F.Fab")
		)
		(fp_line
			(start -0.12065 0.3048)
			(end -0.67945 0.3048)
			(stroke
				(width 0.1)
				(type default)
			)
			(layer "F.Fab")
		)
		(fp_line
			(start -0.67945 0.3048)
			(end -0.67945 -0.305054)
			(stroke
				(width 0.1)
				(type default)
			)
			(layer "F.Fab")
		)
		(pad "1" smd circle
			(at -0.40005 0 90)
			(size 0 0)
			(layers "F.Cu" "F.Mask" "F.Paste")
			(net "CLK_100M_CPU1_CLK12_R_DP")
		)
		(pad "2" smd circle
			(at 0.40005 0 90)
			(size 0 0)
			(layers "F.Cu" "F.Mask" "F.Paste")
			(net "CLK_100M_CPU1_CLK12_DP")
		)
	)
)
